# S9S_MB_2U (Grand Teton) — schematic netlist excerpt (pin names and nets, part order shuffled) for the footprints in the layout excerpt that follows; sources: Cadence DE-HDL packaged netlist, KiCad conversion of 03242023_DA0F0TMBIJ0_F0T_Motherboard_J_brd_V01_OCP.brd

R4103  Q_RES  10K 1% CHIP  pkg 0402LF  page 184 : A = PD_GPP_M_17 ; B = GND
PC289_P0_3  Q_CAP  22UF 4V 20% X6S  pkg C0805  page 268 : A = PVCCIN_CPU0 ; B = GND

(kicad_pcb
	(version 20260206)
	(generator "pcbnew")
	(generator_version "10.0")
	(general
		(thickness 1.6)
		(legacy_teardrops no)
	)
	(paper "A4")
	(title_block
		(title "03242023_DA0F0TMBIJ0_F0T_Motherboard_J_brd_V01_OCP.brd")
		(comment 1 "Grand Teton / footprints 4224-4225 of 6105")
	)
	(layers
		(0 "F.Cu" signal "TOP")
		(4 "In1.Cu" signal "GND")
		(6 "In2.Cu" signal "IN1")
		(8 "In3.Cu" signal "GND1")
		(10 "In4.Cu" signal "IN2")
		(12 "In5.Cu" signal "GND2")
		(14 "In6.Cu" signal "IN3")
		(16 "In7.Cu" signal "GND3")
		(18 "In8.Cu" signal "VCC")
		(20 "In9.Cu" signal "VCC1")
		(22 "In10.Cu" signal "GND4")
		(24 "In11.Cu" signal "IN4")
		(26 "In12.Cu" signal "GND5")
		(28 "In13.Cu" signal "IN5")
		(30 "In14.Cu" signal "GND6")
		(32 "In15.Cu" signal "IN6")
		(34 "In16.Cu" signal "GND7")
		(2 "B.Cu" signal "BOTTOM")
		(9 "F.Adhes" user "F.Adhesive")
		(11 "B.Adhes" user "B.Adhesive")
		(13 "F.Paste" user "Package Geometry/Pastemask Top")
		(15 "B.Paste" user "Package Geometry/Pastemask Bottom")
		(5 "F.SilkS" user "Ref Des/Silkscreen Top")
		(7 "B.SilkS" user "Ref Des/Silkscreen Bottom")
		(1 "F.Mask" user "Board Geometry/Soldermask Top")
		(3 "B.Mask" user "Board Geometry/Soldermask Bottom")
		(17 "Dwgs.User" user "User.Drawings")
		(19 "Cmts.User" user "User.Comments")
		(21 "Eco1.User" user "User.Eco1")
		(23 "Eco2.User" user "User.Eco2")
		(25 "Edge.Cuts" user "Board Geometry/Outline")
		(27 "Margin" user)
		(31 "F.CrtYd" user "Package Geometry/Place Bound Top")
		(29 "B.CrtYd" user "Package Geometry/Place Bound Bottom")
		(35 "F.Fab" user "Ref Des/Assembly Top")
		(33 "B.Fab" user "Ref Des/Assembly Bottom")
	)
	(footprint ""
		(layer "B.Cu")
		(at 311.84088 -52.288948)
		(property "Reference" "R4103"
			(at 0 0 0)
			(layer "B.SilkS")
			(hide yes)
			(effects
				(font
					(size 1.27 1.27)
				)
				(justify mirror)
			)
		)
		(property "Value" ""
			(at 0 0 0)
			(layer "B.Fab")
			(effects
				(font
					(size 1.27 1.27)
				)
				(justify mirror)
			)
		)
		(duplicate_pad_numbers_are_jumpers no)
		(fp_line
			(start -0.7874 -0.4064)
			(end -0.7874 0.4064)
			(stroke
				(width 0.1524)
				(type default)
			)
			(layer "B.SilkS")
		)
		(fp_line
			(start -0.7874 0.4064)
			(end 0.7874 0.4064)
			(stroke
				(width 0.1524)
				(type default)
			)
			(layer "B.SilkS")
		)
		(fp_line
			(start 0.7874 -0.4064)
			(end -0.7874 -0.4064)
			(stroke
				(width 0.1524)
				(type default)
			)
			(layer "B.SilkS")
		)
		(fp_line
			(start 0.7874 0.4064)
			(end 0.7874 -0.4064)
			(stroke
				(width 0.1524)
				(type default)
			)
			(layer "B.SilkS")
		)
		(fp_line
			(start -0.67945 -0.3048)
			(end -0.67945 0.3048)
			(stroke
				(width 0.1)
				(type default)
			)
			(layer "B.Fab")
		)
		(fp_line
			(start -0.67945 0.3048)
			(end -0.120396 0.3048)
			(stroke
				(width 0.1)
				(type default)
			)
			(layer "B.Fab")
		)
		(fp_line
			(start -0.12065 -0.3048)
			(end -0.67945 -0.3048)
			(stroke
				(width 0.1)
				(type default)
			)
			(layer "B.Fab")
		)
		(fp_line
			(start -0.12065 -0.2794)
			(end -0.12065 -0.3048)
			(stroke
				(width 0.1)
				(type default)
			)
			(layer "B.Fab")
		)
		(fp_line
			(start -0.120396 0.2794)
			(end 0.12065 0.2794)
			(stroke
				(width 0.1)
				(type default)
			)
			(layer "B.Fab")
		)
		(fp_line
			(start -0.120396 0.3048)
			(end -0.120396 0.2794)
			(stroke
				(width 0.1)
				(type default)
			)
			(layer "B.Fab")
		)
		(fp_line
			(start 0.12065 -0.305054)
			(end 0.12065 -0.2794)
			(stroke
				(width 0.1)
				(type default)
			)
			(layer "B.Fab")
		)
		(fp_line
			(start 0.12065 -0.2794)
			(end -0.12065 -0.2794)
			(stroke
				(width 0.1)
				(type default)
			)
			(layer "B.Fab")
		)
		(fp_line
			(start 0.12065 0.2794)
			(end 0.12065 0.3048)
			(stroke
				(width 0.1)
				(type default)
			)
			(layer "B.Fab")
		)
		(fp_line
			(start 0.12065 0.3048)
			(end 0.67945 0.3048)
			(stroke
				(width 0.1)
				(type default)
			)
			(layer "B.Fab")
		)
		(fp_line
			(start 0.67945 -0.305054)
			(end 0.12065 -0.305054)
			(stroke
				(width 0.1)
				(type default)
			)
			(layer "B.Fab")
		)
		(fp_line
			(start 0.67945 0.3048)
			(end 0.67945 -0.305054)
			(stroke
				(width 0.1)
				(type default)
			)
			(layer "B.Fab")
		)
		(pad "1" smd circle
			(at 0.40005 0 180)
			(size 0 0)
			(layers "B.Cu" "B.Mask" "B.Paste")
			(net "PD_GPP_M_17")
		)
		(pad "2" smd circle
			(at -0.40005 0 180)
			(size 0 0)
			(layers "B.Cu" "B.Mask" "B.Paste")
			(net "GND")
		)
	)
	(footprint ""
		(layer "B.Cu")
		(at 357.96093 -324.911466 -90)
		(property "Reference" "PC289_P0_3"
			(at 0 0 90)
			(layer "B.SilkS")
			(hide yes)
			(effects
				(font
					(size 1.27 1.27)
				)
				(justify mirror)
			)
		)
		(property "Value" ""
			(at 0 0 90)
			(layer "B.Fab")
			(effects
				(font
					(size 1.27 1.27)
				)
				(justify mirror)
			)
		)
		(duplicate_pad_numbers_are_jumpers no)
		(fp_line
			(start -1.524 0.762)
			(end 1.524 0.762)
			(stroke
				(width 0.1524)
				(type default)
			)
			(layer "B.SilkS")
		)
		(fp_line
			(start 1.524 0.762)
			(end 1.524 -0.762)
			(stroke
				(width 0.1524)
				(type default)
			)
			(layer "B.SilkS")
		)
		(fp_line
			(start -1.524 -0.762)
			(end -1.524 0.762)
			(stroke
				(width 0.1524)
				(type default)
			)
			(layer "B.SilkS")
		)
		(fp_line
			(start 1.524 -0.762)
			(end -1.524 -0.762)
			(stroke
				(width 0.1524)
				(type default)
			)
			(layer "B.SilkS")
		)
		(fp_line
			(start -1.1049 0.724916)
			(end -1.1049 -0.724916)
			(stroke
				(width 0.1)
				(type default)
			)
			(layer "B.Fab")
		)
		(fp_line
			(start 1.1049 0.724916)
			(end -1.1049 0.724916)
			(stroke
				(width 0.1)
				(type default)
			)
			(layer "B.Fab")
		)
		(fp_line
			(start -1.1049 -0.724916)
			(end 1.1049 -0.724916)
			(stroke
				(width 0.1)
				(type default)
			)
			(layer "B.Fab")
		)
		(fp_line
			(start 1.1049 -0.724916)
			(end 1.1049 0.724916)
			(stroke
				(width 0.1)
				(type default)
			)
			(layer "B.Fab")
		)
		(pad "1" smd rect
			(at 0.889 0 270)
			(size 1.016 1.27)
			(layers "B.Cu" "B.Mask" "B.Paste")
			(net "PVCCIN_CPU0")
		)
		(pad "2" smd rect
			(at -0.889 0 270)
			(size 1.016 1.27)
			(layers "B.Cu" "B.Mask" "B.Paste")
			(net "GND")
		)
	)
)
